# SI test board — footprint library table
(fp_lib_table
  (lib (name "si-simulation-test-board-footprints")(type "KiCad")(uri "${KIPRJMOD}/lib/si-simulation-test-board-footprints")(options "")(descr ""))
)
